(kicad_pcb
	(version 20260206)
	(generator "pcbnew")
	(generator_version "10.0")
	(general
		(thickness 1.6)
		(legacy_teardrops no)
	)
	(paper "A4")
	(title_block
		(title "03242023_DA0F0TMBIJ0_F0T_Motherboard_J_brd_V01_OCP.brd")
		(comment 1 "Grand Teton / footprints 5948-5954 of 6105")
	)
	(layers
		(0 "F.Cu" signal "TOP")
		(4 "In1.Cu" signal "GND")
		(6 "In2.Cu" signal "IN1")
		(8 "In3.Cu" signal "GND1")
		(10 "In4.Cu" signal "IN2")
		(12 "In5.Cu" signal "GND2")
		(14 "In6.Cu" signal "IN3")
		(16 "In7.Cu" signal "GND3")
		(18 "In8.Cu" signal "VCC")
		(20 "In9.Cu" signal "VCC1")
		(22 "In10.Cu" signal "GND4")
		(24 "In11.Cu" signal "IN4")
		(26 "In12.Cu" signal "GND5")
		(28 "In13.Cu" signal "IN5")
		(30 "In14.Cu" signal "GND6")
		(32 "In15.Cu" signal "IN6")
		(34 "In16.Cu" signal "GND7")
		(2 "B.Cu" signal "BOTTOM")
		(9 "F.Adhes" user "F.Adhesive")
		(11 "B.Adhes" user "B.Adhesive")
		(13 "F.Paste" user "Package Geometry/Pastemask Top")
		(15 "B.Paste" user "Package Geometry/Pastemask Bottom")
		(5 "F.SilkS" user "Ref Des/Silkscreen Top")
		(7 "B.SilkS" user "Ref Des/Silkscreen Bottom")
		(1 "F.Mask" user "Board Geometry/Soldermask Top")
		(3 "B.Mask" user "Board Geometry/Soldermask Bottom")
		(17 "Dwgs.User" user "User.Drawings")
		(19 "Cmts.User" user "User.Comments")
		(21 "Eco1.User" user "User.Eco1")
		(23 "Eco2.User" user "User.Eco2")
		(25 "Edge.Cuts" user "Board Geometry/Outline")
		(27 "Margin" user)
		(31 "F.CrtYd" user "Package Geometry/Place Bound Top")
		(29 "B.CrtYd" user "Package Geometry/Place Bound Bottom")
		(35 "F.Fab" user "Ref Des/Assembly Top")
		(33 "B.Fab" user "Ref Des/Assembly Bottom")
	)
	(footprint ""
		(layer "B.Cu")
		(at 194.159378 -193.43497)
		(property "Reference" "C543"
			(at 0 0 0)
			(layer "B.SilkS")
			(hide yes)
			(effects
				(font
					(size 1.27 1.27)
				)
				(justify mirror)
			)
		)
		(property "Value" ""
			(at 0 0 0)
			(layer "B.Fab")
			(effects
				(font
					(size 1.27 1.27)
				)
				(justify mirror)
			)
		)
		(duplicate_pad_numbers_are_jumpers no)
		(fp_line
			(start -0.7874 -0.4064)
			(end -0.7874 0.4064)
			(stroke
				(width 0.1524)
				(type default)
			)
			(layer "B.SilkS")
		)
		(fp_line
			(start -0.7874 0.4064)
			(end 0.7874 0.4064)
			(stroke
				(width 0.1524)
				(type default)
			)
			(layer "B.SilkS")
		)
		(fp_line
			(start 0.7874 -0.4064)
			(end -0.7874 -0.4064)
			(stroke
				(width 0.1524)
				(type default)
			)
			(layer "B.SilkS")
		)
		(fp_line
			(start 0.7874 0.4064)
			(end 0.7874 -0.4064)
			(stroke
				(width 0.1524)
				(type default)
			)
			(layer "B.SilkS")
		)
		(fp_line
			(start -0.67945 -0.3048)
			(end -0.67945 0.3048)
			(stroke
				(width 0.1)
				(type default)
			)
			(layer "B.Fab")
		)
		(fp_line
			(start -0.67945 0.3048)
			(end -0.120396 0.3048)
			(stroke
				(width 0.1)
				(type default)
			)
			(layer "B.Fab")
		)
		(fp_line
			(start -0.12065 -0.3048)
			(end -0.67945 -0.3048)
			(stroke
				(width 0.1)
				(type default)
			)
			(layer "B.Fab")
		)
		(fp_line
			(start -0.12065 -0.2794)
			(end -0.12065 -0.3048)
			(stroke
				(width 0.1)
				(type default)
			)
			(layer "B.Fab")
		)
		(fp_line
			(start -0.120396 0.2794)
			(end 0.12065 0.2794)
			(stroke
				(width 0.1)
				(type default)
			)
			(layer "B.Fab")
		)
		(fp_line
			(start -0.120396 0.3048)
			(end -0.120396 0.2794)
			(stroke
				(width 0.1)
				(type default)
			)
			(layer "B.Fab")
		)
		(fp_line
			(start 0.12065 -0.305054)
			(end 0.12065 -0.2794)
			(stroke
				(width 0.1)
				(type default)
			)
			(layer "B.Fab")
		)
		(fp_line
			(start 0.12065 -0.2794)
			(end -0.12065 -0.2794)
			(stroke
				(width 0.1)
				(type default)
			)
			(layer "B.Fab")
		)
		(fp_line
			(start 0.12065 0.2794)
			(end 0.12065 0.3048)
			(stroke
				(width 0.1)
				(type default)
			)
			(layer "B.Fab")
		)
		(fp_line
			(start 0.12065 0.3048)
			(end 0.67945 0.3048)
			(stroke
				(width 0.1)
				(type default)
			)
			(layer "B.Fab")
		)
		(fp_line
			(start 0.67945 -0.305054)
			(end 0.12065 -0.305054)
			(stroke
				(width 0.1)
				(type default)
			)
			(layer "B.Fab")
		)
		(fp_line
			(start 0.67945 0.3048)
			(end 0.67945 -0.305054)
			(stroke
				(width 0.1)
				(type default)
			)
			(layer "B.Fab")
		)
		(pad "1" smd circle
			(at 0.40005 0 180)
			(size 0 0)
			(layers "B.Cu" "B.Mask" "B.Paste")
			(net "P3V3_AUX")
		)
		(pad "2" smd circle
			(at -0.40005 0 180)
			(size 0 0)
			(layers "B.Cu" "B.Mask" "B.Paste")
			(net "GND")
		)
	)
	(footprint ""
		(layer "B.Cu")
		(at 131.74726 -28.20924)
		(property "Reference" "C2349"
			(at 0 0 0)
			(layer "B.SilkS")
			(hide yes)
			(effects
				(font
					(size 1.27 1.27)
				)
				(justify mirror)
			)
		)
		(property "Value" ""
			(at 0 0 0)
			(layer "B.Fab")
			(effects
				(font
					(size 1.27 1.27)
				)
				(justify mirror)
			)
		)
		(duplicate_pad_numbers_are_jumpers no)
		(fp_line
			(start -0.40005 0.4064)
			(end 0.40005 0.4064)
			(stroke
				(width 0.1524)
				(type default)
			)
			(layer "B.SilkS")
		)
		(fp_line
			(start 0.40005 -0.4064)
			(end -0.40005 -0.4064)
			(stroke
				(width 0.1524)
				(type default)
			)
			(layer "B.SilkS")
		)
		(fp_line
			(start -0.6858 -0.3048)
			(end -0.6858 0.3048)
			(stroke
				(width 0.1)
				(type default)
			)
			(layer "B.Fab")
		)
		(fp_line
			(start -0.6858 0.3048)
			(end -0.1016 0.3048)
			(stroke
				(width 0.1)
				(type default)
			)
			(layer "B.Fab")
		)
		(fp_line
			(start -0.1016 -0.3048)
			(end -0.6858 -0.3048)
			(stroke
				(width 0.1)
				(type default)
			)
			(layer "B.Fab")
		)
		(fp_line
			(start -0.1016 -0.2794)
			(end -0.1016 -0.3048)
			(stroke
				(width 0.1)
				(type default)
			)
			(layer "B.Fab")
		)
		(fp_line
			(start -0.1016 0.2794)
			(end 0.1016 0.2794)
			(stroke
				(width 0.1)
				(type default)
			)
			(layer "B.Fab")
		)
		(fp_line
			(start -0.1016 0.3048)
			(end -0.1016 0.2794)
			(stroke
				(width 0.1)
				(type default)
			)
			(layer "B.Fab")
		)
		(fp_line
			(start 0.1016 -0.3048)
			(end 0.1016 -0.2794)
			(stroke
				(width 0.1)
				(type default)
			)
			(layer "B.Fab")
		)
		(fp_line
			(start 0.1016 -0.2794)
			(end -0.1016 -0.2794)
			(stroke
				(width 0.1)
				(type default)
			)
			(layer "B.Fab")
		)
		(fp_line
			(start 0.1016 0.2794)
			(end 0.1016 0.3048)
			(stroke
				(width 0.1)
				(type default)
			)
			(layer "B.Fab")
		)
		(fp_line
			(start 0.1016 0.3048)
			(end 0.6858 0.3048)
			(stroke
				(width 0.1)
				(type default)
			)
			(layer "B.Fab")
		)
		(fp_line
			(start 0.6858 -0.3048)
			(end 0.1016 -0.3048)
			(stroke
				(width 0.1)
				(type default)
			)
			(layer "B.Fab")
		)
		(fp_line
			(start 0.6858 0.3048)
			(end 0.6858 -0.3048)
			(stroke
				(width 0.1)
				(type default)
			)
			(layer "B.Fab")
		)
		(pad "1" smd rect
			(at 0.40005 0)
			(size 0.4572 0.508)
			(layers "B.Cu" "B.Mask" "B.Paste")
			(net "USB3_PCH_RX_DP<4>")
		)
		(pad "2" smd rect
			(at -0.40005 0)
			(size 0.4572 0.508)
			(layers "B.Cu" "B.Mask" "B.Paste")
			(net "USB3_PCH_RX_C_DP<4>")
		)
		(zone
			(layer "In16.Cu")
			(hatch none 0.5)
			(connect_pads
				(clearance 0)
			)
			(min_thickness 0.25)
			(keepout
				(tracks not_allowed)
				(vias allowed)
				(pads allowed)
				(copperpour not_allowed)
				(footprints allowed)
			)
			(placement
				(enabled no)
				(sheetname "")
			)
			(fill
				(thermal_gap 0.5)
				(thermal_bridge_width 0.5)
				(island_removal_mode 0)
			)
			(polygon
				(pts
					(xy 131.62661 -27.90444) (xy 131.06781 -27.90444) (xy 131.06781 -28.51404) (xy 131.62661 -28.51404)
				)
			)
		)
		(zone
			(layer "In16.Cu")
			(hatch none 0.5)
			(connect_pads
				(clearance 0)
			)
			(min_thickness 0.25)
			(keepout
				(tracks not_allowed)
				(vias allowed)
				(pads allowed)
				(copperpour not_allowed)
				(footprints allowed)
			)
			(placement
				(enabled no)
				(sheetname "")
			)
			(fill
				(thermal_gap 0.5)
				(thermal_bridge_width 0.5)
				(island_removal_mode 0)
			)
			(polygon
				(pts
					(xy 132.42671 -27.90444) (xy 131.86791 -27.90444) (xy 131.86791 -28.51404) (xy 132.42671 -28.51404)
				)
			)
		)
	)
	(footprint ""
		(layer "B.Cu")
		(at 89.343484 -181.450488 90)
		(property "Reference" "Q16"
			(at 0.79121 4.346956 0)
			(unlocked yes)
			(layer "B.SilkS")
			(effects
				(font
					(size 0.7874 0.5842)
					(thickness 0.1524)
				)
				(justify left mirror)
			)
		)
		(property "Value" ""
			(at 0 0 90)
			(layer "B.Fab")
			(effects
				(font
					(size 1.27 1.27)
				)
				(justify mirror)
			)
		)
		(duplicate_pad_numbers_are_jumpers no)
		(fp_line
			(start 1.332738 -1.100074)
			(end 0.4826 -1.100074)
			(stroke
				(width 0.1524)
				(type default)
			)
			(layer "B.SilkS")
		)
		(fp_line
			(start 0.4826 -1.100074)
			(end 0 -0.541274)
			(stroke
				(width 0.1524)
				(type default)
			)
			(layer "B.SilkS")
		)
		(fp_line
			(start -0.4826 -1.100074)
			(end -1.332738 -1.100074)
			(stroke
				(width 0.1524)
				(type default)
			)
			(layer "B.SilkS")
		)
		(fp_line
			(start -1.332738 -1.100074)
			(end -1.332738 1.100074)
			(stroke
				(width 0.1524)
				(type default)
			)
			(layer "B.SilkS")
		)
		(fp_line
			(start 0 -0.541274)
			(end -0.4826 -1.100074)
			(stroke
				(width 0.1524)
				(type default)
			)
			(layer "B.SilkS")
		)
		(fp_line
			(start 1.332738 1.100074)
			(end 1.332738 -1.100074)
			(stroke
				(width 0.1524)
				(type default)
			)
			(layer "B.SilkS")
		)
		(fp_line
			(start -1.332738 1.100074)
			(end 1.332738 1.100074)
			(stroke
				(width 0.1524)
				(type default)
			)
			(layer "B.SilkS")
		)
		(fp_poly
			(pts
				(xy 1.50749 -2.152904) (xy 1.156462 -1.450848) (xy 0.805434 -2.152904)
			)
			(stroke
				(width 0)
				(type default)
			)
			(fill yes)
			(layer "B.SilkS")
		)
		(fp_line
			(start 0.674878 -1.100074)
			(end -0.674878 -1.100074)
			(stroke
				(width 0.1)
				(type default)
			)
			(layer "B.Fab")
		)
		(fp_line
			(start -0.674878 -1.100074)
			(end -0.674878 1.100074)
			(stroke
				(width 0.1)
				(type default)
			)
			(layer "B.Fab")
		)
		(fp_line
			(start 0.674878 1.100074)
			(end 0.674878 -1.100074)
			(stroke
				(width 0.1)
				(type default)
			)
			(layer "B.Fab")
		)
		(fp_line
			(start -0.674878 1.100074)
			(end 0.674878 1.100074)
			(stroke
				(width 0.1)
				(type default)
			)
			(layer "B.Fab")
		)
		(fp_poly
			(pts
				(xy 2.2352 -0.298958) (xy 2.2352 -1.001014) (xy 1.533144 -0.649986)
			)
			(stroke
				(width 0)
				(type default)
			)
			(fill yes)
			(layer "B.Fab")
		)
		(pad "1" smd rect
			(at 0.94996 -0.649986 180)
			(size 0.4318 0.508)
			(layers "B.Cu" "B.Mask" "B.Paste")
			(net "GND")
		)
		(pad "2" smd rect
			(at 0.94996 0 180)
			(size 0.4318 0.508)
			(layers "B.Cu" "B.Mask" "B.Paste")
			(net "FM_SMB_PEHPCPU1_PCIE_ALERT_R_N")
		)
		(pad "3" smd rect
			(at 0.94996 0.649986 180)
			(size 0.4318 0.508)
			(layers "B.Cu" "B.Mask" "B.Paste")
			(net "FM_PEHPCPU1_ALERT_N")
		)
		(pad "4" smd rect
			(at -0.94996 0.649986 180)
			(size 0.4318 0.508)
			(layers "B.Cu" "B.Mask" "B.Paste")
			(net "GND")
		)
		(pad "5" smd rect
			(at -0.94996 0 180)
			(size 0.4318 0.508)
			(layers "B.Cu" "B.Mask" "B.Paste")
			(net "FM_SMB_CPU1_ALERT_R1")
		)
		(pad "6" smd rect
			(at -0.94996 -0.649986 180)
			(size 0.4318 0.508)
			(layers "B.Cu" "B.Mask" "B.Paste")
			(net "FM_SMB_CPU1_ALERT_R1")
		)
	)
	(footprint ""
		(layer "B.Cu")
		(at 376.468132 -76.696824 180)
		(property "Reference" "PC1239"
			(at 0 0 0)
			(layer "B.SilkS")
			(hide yes)
			(effects
				(font
					(size 1.27 1.27)
				)
				(justify mirror)
			)
		)
		(property "Value" ""
			(at 0 0 0)
			(layer "B.Fab")
			(effects
				(font
					(size 1.27 1.27)
				)
				(justify mirror)
			)
		)
		(duplicate_pad_numbers_are_jumpers no)
		(fp_line
			(start 1.524 0.762)
			(end 1.524 -0.762)
			(stroke
				(width 0.1524)
				(type default)
			)
			(layer "B.SilkS")
		)
		(fp_line
			(start 1.524 -0.762)
			(end -1.524 -0.762)
			(stroke
				(width 0.1524)
				(type default)
			)
			(layer "B.SilkS")
		)
		(fp_line
			(start -1.524 0.762)
			(end 1.524 0.762)
			(stroke
				(width 0.1524)
				(type default)
			)
			(layer "B.SilkS")
		)
		(fp_line
			(start -1.524 -0.762)
			(end -1.524 0.762)
			(stroke
				(width 0.1524)
				(type default)
			)
			(layer "B.SilkS")
		)
		(fp_line
			(start 1.1049 0.724916)
			(end -1.1049 0.724916)
			(stroke
				(width 0.1)
				(type default)
			)
			(layer "B.Fab")
		)
		(fp_line
			(start 1.1049 -0.724916)
			(end 1.1049 0.724916)
			(stroke
				(width 0.1)
				(type default)
			)
			(layer "B.Fab")
		)
		(fp_line
			(start -1.1049 0.724916)
			(end -1.1049 -0.724916)
			(stroke
				(width 0.1)
				(type default)
			)
			(layer "B.Fab")
		)
		(fp_line
			(start -1.1049 -0.724916)
			(end 1.1049 -0.724916)
			(stroke
				(width 0.1)
				(type default)
			)
			(layer "B.Fab")
		)
		(pad "1" smd rect
			(at 0.889 0 180)
			(size 1.016 1.27)
			(layers "B.Cu" "B.Mask" "B.Paste")
			(net "P1V8_PCH_AUX")
		)
		(pad "2" smd rect
			(at -0.889 0 180)
			(size 1.016 1.27)
			(layers "B.Cu" "B.Mask" "B.Paste")
			(net "GND")
		)
	)
	(footprint ""
		(layer "B.Cu")
		(at 178.04384 -32.944308 90)
		(property "Reference" "PC2340"
			(at 0 0 90)
			(layer "B.SilkS")
			(hide yes)
			(effects
				(font
					(size 1.27 1.27)
				)
				(justify mirror)
			)
		)
		(property "Value" ""
			(at 0 0 90)
			(layer "B.Fab")
			(effects
				(font
					(size 1.27 1.27)
				)
				(justify mirror)
			)
		)
		(duplicate_pad_numbers_are_jumpers no)
		(fp_line
			(start 0.7874 -0.4064)
			(end -0.7874 -0.4064)
			(stroke
				(width 0.1524)
				(type default)
			)
			(layer "B.SilkS")
		)
		(fp_line
			(start -0.7874 -0.4064)
			(end -0.7874 0.4064)
			(stroke
				(width 0.1524)
				(type default)
			)
			(layer "B.SilkS")
		)
		(fp_line
			(start 0.7874 0.4064)
			(end 0.7874 -0.4064)
			(stroke
				(width 0.1524)
				(type default)
			)
			(layer "B.SilkS")
		)
		(fp_line
			(start -0.7874 0.4064)
			(end 0.7874 0.4064)
			(stroke
				(width 0.1524)
				(type default)
			)
			(layer "B.SilkS")
		)
		(fp_line
			(start 0.67945 -0.305054)
			(end 0.12065 -0.305054)
			(stroke
				(width 0.1)
				(type default)
			)
			(layer "B.Fab")
		)
		(fp_line
			(start 0.12065 -0.305054)
			(end 0.12065 -0.2794)
			(stroke
				(width 0.1)
				(type default)
			)
			(layer "B.Fab")
		)
		(fp_line
			(start -0.12065 -0.3048)
			(end -0.67945 -0.3048)
			(stroke
				(width 0.1)
				(type default)
			)
			(layer "B.Fab")
		)
		(fp_line
			(start -0.67945 -0.3048)
			(end -0.67945 0.3048)
			(stroke
				(width 0.1)
				(type default)
			)
			(layer "B.Fab")
		)
		(fp_line
			(start 0.12065 -0.2794)
			(end -0.12065 -0.2794)
			(stroke
				(width 0.1)
				(type default)
			)
			(layer "B.Fab")
		)
		(fp_line
			(start -0.12065 -0.2794)
			(end -0.12065 -0.3048)
			(stroke
				(width 0.1)
				(type default)
			)
			(layer "B.Fab")
		)
		(fp_line
			(start 0.12065 0.2794)
			(end 0.12065 0.3048)
			(stroke
				(width 0.1)
				(type default)
			)
			(layer "B.Fab")
		)
		(fp_line
			(start -0.120396 0.2794)
			(end 0.12065 0.2794)
			(stroke
				(width 0.1)
				(type default)
			)
			(layer "B.Fab")
		)
		(fp_line
			(start 0.67945 0.3048)
			(end 0.67945 -0.305054)
			(stroke
				(width 0.1)
				(type default)
			)
			(layer "B.Fab")
		)
		(fp_line
			(start 0.12065 0.3048)
			(end 0.67945 0.3048)
			(stroke
				(width 0.1)
				(type default)
			)
			(layer "B.Fab")
		)
		(fp_line
			(start -0.120396 0.3048)
			(end -0.120396 0.2794)
			(stroke
				(width 0.1)
				(type default)
			)
			(layer "B.Fab")
		)
		(fp_line
			(start -0.67945 0.3048)
			(end -0.120396 0.3048)
			(stroke
				(width 0.1)
				(type default)
			)
			(layer "B.Fab")
		)
		(pad "1" smd circle
			(at 0.40005 0 270)
			(size 0 0)
			(layers "B.Cu" "B.Mask" "B.Paste")
			(net "P12V_SCM_ISET_R")
		)
		(pad "2" smd circle
			(at -0.40005 0 270)
			(size 0 0)
			(layers "B.Cu" "B.Mask" "B.Paste")
			(net "GND")
		)
	)
	(footprint ""
		(layer "B.Cu")
		(at 105.595928 -262.34898)
		(property "Reference" "C312"
			(at 0 0 0)
			(layer "B.SilkS")
			(hide yes)
			(effects
				(font
					(size 1.27 1.27)
				)
				(justify mirror)
			)
		)
		(property "Value" ""
			(at 0 0 0)
			(layer "B.Fab")
			(effects
				(font
					(size 1.27 1.27)
				)
				(justify mirror)
			)
		)
		(duplicate_pad_numbers_are_jumpers no)
		(fp_line
			(start -1.524 -0.762)
			(end -1.524 0.762)
			(stroke
				(width 0.1524)
				(type default)
			)
			(layer "B.SilkS")
		)
		(fp_line
			(start -1.524 0.762)
			(end 1.524 0.762)
			(stroke
				(width 0.1524)
				(type default)
			)
			(layer "B.SilkS")
		)
		(fp_line
			(start 1.524 -0.762)
			(end -1.524 -0.762)
			(stroke
				(width 0.1524)
				(type default)
			)
			(layer "B.SilkS")
		)
		(fp_line
			(start 1.524 0.762)
			(end 1.524 -0.762)
			(stroke
				(width 0.1524)
				(type default)
			)
			(layer "B.SilkS")
		)
		(fp_line
			(start -1.1049 -0.724916)
			(end 1.1049 -0.724916)
			(stroke
				(width 0.1)
				(type default)
			)
			(layer "B.Fab")
		)
		(fp_line
			(start -1.1049 0.724916)
			(end -1.1049 -0.724916)
			(stroke
				(width 0.1)
				(type default)
			)
			(layer "B.Fab")
		)
		(fp_line
			(start 1.1049 -0.724916)
			(end 1.1049 0.724916)
			(stroke
				(width 0.1)
				(type default)
			)
			(layer "B.Fab")
		)
		(fp_line
			(start 1.1049 0.724916)
			(end -1.1049 0.724916)
			(stroke
				(width 0.1)
				(type default)
			)
			(layer "B.Fab")
		)
		(pad "1" smd rect
			(at 0.889 0)
			(size 1.016 1.27)
			(layers "B.Cu" "B.Mask" "B.Paste")
			(net "PVCCIN_CPU1")
		)
		(pad "2" smd rect
			(at -0.889 0)
			(size 1.016 1.27)
			(layers "B.Cu" "B.Mask" "B.Paste")
			(net "GND")
		)
	)
	(footprint ""
		(layer "B.Cu")
		(at 104.463088 -212.049868)
		(property "Reference" "C464"
			(at 0 0 0)
			(layer "B.SilkS")
			(hide yes)
			(effects
				(font
					(size 1.27 1.27)
				)
				(justify mirror)
			)
		)
		(property "Value" ""
			(at 0 0 0)
			(layer "B.Fab")
			(effects
				(font
					(size 1.27 1.27)
				)
				(justify mirror)
			)
		)
		(duplicate_pad_numbers_are_jumpers no)
		(fp_line
			(start -1.524 -0.762)
			(end -1.524 0.762)
			(stroke
				(width 0.1524)
				(type default)
			)
			(layer "B.SilkS")
		)
		(fp_line
			(start -1.524 0.762)
			(end 1.524 0.762)
			(stroke
				(width 0.1524)
				(type default)
			)
			(layer "B.SilkS")
		)
		(fp_line
			(start 1.524 -0.762)
			(end -1.524 -0.762)
			(stroke
				(width 0.1524)
				(type default)
			)
			(layer "B.SilkS")
		)
		(fp_line
			(start 1.524 0.762)
			(end 1.524 -0.762)
			(stroke
				(width 0.1524)
				(type default)
			)
			(layer "B.SilkS")
		)
		(fp_line
			(start -1.1049 -0.724916)
			(end 1.1049 -0.724916)
			(stroke
				(width 0.1)
				(type default)
			)
			(layer "B.Fab")
		)
		(fp_line
			(start -1.1049 0.724916)
			(end -1.1049 -0.724916)
			(stroke
				(width 0.1)
				(type default)
			)
			(layer "B.Fab")
		)
		(fp_line
			(start 1.1049 -0.724916)
			(end 1.1049 0.724916)
			(stroke
				(width 0.1)
				(type default)
			)
			(layer "B.Fab")
		)
		(fp_line
			(start 1.1049 0.724916)
			(end -1.1049 0.724916)
			(stroke
				(width 0.1)
				(type default)
			)
			(layer "B.Fab")
		)
		(pad "1" smd rect
			(at 0.889 0)
			(size 1.016 1.27)
			(layers "B.Cu" "B.Mask" "B.Paste")
			(net "PVCCFA_EHV_CPU1")
		)
		(pad "2" smd rect
			(at -0.889 0)
			(size 1.016 1.27)
			(layers "B.Cu" "B.Mask" "B.Paste")
			(net "GND")
		)
	)
)
